FILE_TYPE = MACRO_DRAWING;
SET COLOR_WIRE YELLOW;
SET COLOR_PROP ORANGE;
SET COLOR_DOT WHITE;
SET COLOR_ARC YELLOW;
SET COLOR_BODY GREEN;
SET COLOR_NOTE PURPLE;
SET PROP_DISPLAY VALUE;
SET PAGE_NUMBER P452;
FORCEADD P1V0..1
(-7525 5100);
FORCEPROP 3 LASTPIN (-7525 5050) SIG_NAME P1V8_CPU1_RT2_1A\g
J 0
(-7515 5060);
DISPLAY 0.659574 (-7515 5060);
PAINT MONO (-7515 5060);
DISPLAY INVISIBLE (-7515 5060);
FORCEPROP 1 LAST HDL_POWER P1V8_CPU1_RT2_1A
J 1
(-7525 5150);
DISPLAY 0.489362 (-7525 5150);
PAINT SKYBLUE (-7525 5150);
FORCEPROP 2 LAST CDS_LIB pure_quanta_power
J 0
(-7525 5100);
DISPLAY INVISIBLE (-7525 5100);
FORCEPROP 1 LAST PATH I10
J 0
(-7475 5125);
DISPLAY 0.872340 (-7475 5125);
PAINT AQUA (-7475 5125);
DISPLAY INVISIBLE (-7475 5125);
FORCEADD VCC_CORE..1
(-5000 4800);
FORCEPROP 3 LASTPIN (-5000 4750) SIG_NAME P0V9_CPU1_RT2_2A_2D\g
J 0
(-4990 4760);
DISPLAY 0.659574 (-4990 4760);
PAINT MONO (-4990 4760);
DISPLAY INVISIBLE (-4990 4760);
FORCEPROP 1 LAST HDL_POWER P0V9_CPU1_RT2_2A_2D
J 1
(-5000 4850);
DISPLAY 0.617021 (-5000 4850);
PAINT GREEN (-5000 4850);
FORCEPROP 2 LAST CDS_LIB pure_quanta_power
J 0
(-5000 4800);
DISPLAY INVISIBLE (-5000 4800);
FORCEPROP 1 LAST PATH I11
J 0
(-4950 4825);
DISPLAY 0.872340 (-4950 4825);
PAINT AQUA (-4950 4825);
DISPLAY INVISIBLE (-4950 4825);
FORCEADD VCC_CORE..1
(-4425 5275);
FORCEPROP 3 LASTPIN (-4425 5225) SIG_NAME P0V9_CPU1_RT2_2A\g
J 0
(-4415 5235);
DISPLAY 0.659574 (-4415 5235);
PAINT MONO (-4415 5235);
DISPLAY INVISIBLE (-4415 5235);
FORCEPROP 1 LAST HDL_POWER P0V9_CPU1_RT2_2A
J 1
(-4425 5325);
DISPLAY 0.617021 (-4425 5325);
PAINT GREEN (-4425 5325);
FORCEPROP 2 LAST CDS_LIB pure_quanta_power
J 0
(-4425 5275);
DISPLAY INVISIBLE (-4425 5275);
FORCEPROP 1 LAST PATH I12
J 0
(-4375 5300);
DISPLAY 0.872340 (-4375 5300);
PAINT AQUA (-4375 5300);
DISPLAY INVISIBLE (-4375 5300);
FORCEADD UNIVERSAL_GND..1
(-2875 1575);
FORCEPROP 3 LASTPIN (-2875 1625) SIG_NAME GND\g
J 0
(-2865 1635);
DISPLAY 0.659574 (-2865 1635);
PAINT MONO (-2865 1635);
DISPLAY INVISIBLE (-2865 1635);
FORCEPROP 2 LAST CDS_LIB pure_quanta_power
J 0
(-2875 1575);
DISPLAY INVISIBLE (-2875 1575);
FORCEPROP 1 LAST HDL_POWER GND
J 1
(-2850 1500);
DISPLAY 0.872340 (-2850 1500);
PAINT GREEN (-2850 1500);
DISPLAY INVISIBLE (-2850 1500);
FORCEPROP 1 LAST PATH I13
J 0
(-2800 1575);
DISPLAY 0.872340 (-2800 1575);
PAINT AQUA (-2800 1575);
DISPLAY INVISIBLE (-2800 1575);
FORCEADD UNIVERSAL_GND..1
(-1200 1200);
FORCEPROP 3 LASTPIN (-1200 1250) SIG_NAME GND\g
J 0
(-1190 1260);
DISPLAY 0.659574 (-1190 1260);
PAINT MONO (-1190 1260);
DISPLAY INVISIBLE (-1190 1260);
FORCEPROP 2 LAST CDS_LIB pure_quanta_power
J 0
(-1200 1200);
DISPLAY INVISIBLE (-1200 1200);
FORCEPROP 1 LAST HDL_POWER GND
J 1
(-1175 1125);
DISPLAY 0.872340 (-1175 1125);
PAINT GREEN (-1175 1125);
DISPLAY INVISIBLE (-1175 1125);
FORCEPROP 1 LAST PATH I14
J 0
(-1125 1200);
DISPLAY 0.872340 (-1125 1200);
PAINT AQUA (-1125 1200);
DISPLAY INVISIBLE (-1125 1200);
FORCEADD Q_RES..2
(-1200 1500);
FORCEPROP 1 LAST LOCATION R6797
J 0
(-1155 1625);
DISPLAY 0.978723 (-1155 1625);
FORCEPROP 0 LAST $SEC 1
J 0
(-1150 1675);
DISPLAY 0.680851 (-1150 1675);
PAINT MONO (-1150 1675);
DISPLAY INVISIBLE (-1150 1675);
FORCEPROP 0 LAST CDS_SEC 1
J 0
(-1150 1675);
DISPLAY 0.680851 (-1150 1675);
DISPLAY INVISIBLE (-1150 1675);
FORCEPROP 1 LASTPIN (-1200 1600) $PN 1
J 0
(-1195 1562);
DISPLAY 0.787234 (-1195 1562);
PAINT MONO (-1195 1562);
FORCEPROP 1 LASTPIN (-1200 1400) $PN 2
J 0
(-1195 1410);
DISPLAY 0.787234 (-1195 1410);
PAINT MONO (-1195 1410);
FORCEPROP 1 LAST MATERIAL CHIP
J 0
(-1160 1425);
DISPLAY 0.978723 (-1160 1425);
FORCEPROP 1 LAST PACK_TYPE 0201LF
J 0
(-1160 1325);
DISPLAY 0.978723 (-1160 1325);
FORCEPROP 1 LAST TOLERANCE 5%
J 0
(-1155 1525);
DISPLAY 0.978723 (-1155 1525);
FORCEPROP 1 LAST WATTAGE 1/20W
J 0
(-1160 1475);
DISPLAY 0.978723 (-1160 1475);
FORCEPROP 1 LAST VALUE 0
J 0
(-1155 1575);
DISPLAY 0.978723 (-1155 1575);
FORCEPROP 2 LAST CDS_LIB pure_quanta
J 0
(-1200 1500);
DISPLAY INVISIBLE (-1200 1500);
FORCEPROP 1 LAST PATH I15
J 0
(-1150 1675);
DISPLAY 0.978723 (-1150 1675);
PAINT WHITE (-1150 1675);
DISPLAY INVISIBLE (-1150 1675);
FORCEPROP 1 LAST PART_NUMBER CS00001JE10
J 0
(-1160 1375);
DISPLAY 0.978723 (-1160 1375);
DISPLAY INVISIBLE (-1160 1375);
FORCEADD UNIVERSAL_GND..1
(-1050 1750);
FORCEPROP 3 LASTPIN (-1050 1800) SIG_NAME GND\g
J 0
(-1040 1810);
DISPLAY 0.659574 (-1040 1810);
PAINT MONO (-1040 1810);
DISPLAY INVISIBLE (-1040 1810);
FORCEPROP 2 LAST CDS_LIB pure_quanta_power
J 0
(-1050 1750);
DISPLAY INVISIBLE (-1050 1750);
FORCEPROP 1 LAST HDL_POWER GND
J 1
(-1025 1675);
DISPLAY 0.872340 (-1025 1675);
PAINT GREEN (-1025 1675);
DISPLAY INVISIBLE (-1025 1675);
FORCEPROP 1 LAST PATH I16
J 0
(-975 1750);
DISPLAY 0.872340 (-975 1750);
PAINT AQUA (-975 1750);
DISPLAY INVISIBLE (-975 1750);
FORCEADD UNIVERSAL_GND..1
(-825 2300);
FORCEPROP 3 LASTPIN (-825 2350) SIG_NAME GND\g
J 0
(-815 2360);
DISPLAY 0.659574 (-815 2360);
PAINT MONO (-815 2360);
DISPLAY INVISIBLE (-815 2360);
FORCEPROP 2 LAST CDS_LIB pure_quanta_power
J 0
(-825 2300);
DISPLAY INVISIBLE (-825 2300);
FORCEPROP 1 LAST HDL_POWER GND
J 1
(-800 2225);
DISPLAY 0.872340 (-800 2225);
PAINT GREEN (-800 2225);
DISPLAY INVISIBLE (-800 2225);
FORCEPROP 1 LAST PATH I17
J 0
(-750 2300);
DISPLAY 0.872340 (-750 2300);
PAINT AQUA (-750 2300);
DISPLAY INVISIBLE (-750 2300);
FORCEADD Q_RES..2
(-1050 2050);
FORCEPROP 1 LAST LOCATION R6796
J 0
(-1005 2175);
DISPLAY 0.978723 (-1005 2175);
FORCEPROP 0 LAST $SEC 1
J 0
(-1000 2225);
DISPLAY 0.680851 (-1000 2225);
PAINT MONO (-1000 2225);
DISPLAY INVISIBLE (-1000 2225);
FORCEPROP 0 LAST CDS_SEC 1
J 0
(-1000 2225);
DISPLAY 0.680851 (-1000 2225);
DISPLAY INVISIBLE (-1000 2225);
FORCEPROP 1 LASTPIN (-1050 2150) $PN 1
J 0
(-1045 2112);
DISPLAY 0.787234 (-1045 2112);
PAINT MONO (-1045 2112);
FORCEPROP 1 LASTPIN (-1050 1950) $PN 2
J 0
(-1045 1960);
DISPLAY 0.787234 (-1045 1960);
PAINT MONO (-1045 1960);
FORCEPROP 1 LAST PACK_TYPE 0201LF
J 0
(-1010 1875);
DISPLAY 0.978723 (-1010 1875);
FORCEPROP 1 LAST MATERIAL CHIP
J 0
(-1010 1975);
DISPLAY 0.978723 (-1010 1975);
FORCEPROP 1 LAST WATTAGE 1/20W
J 0
(-1010 2025);
DISPLAY 0.978723 (-1010 2025);
FORCEPROP 1 LAST TOLERANCE 5%
J 0
(-1005 2075);
DISPLAY 0.978723 (-1005 2075);
FORCEPROP 1 LAST VALUE 0
J 0
(-1005 2125);
DISPLAY 0.978723 (-1005 2125);
FORCEPROP 2 LAST CDS_LIB pure_quanta
J 0
(-1050 2050);
DISPLAY INVISIBLE (-1050 2050);
FORCEPROP 1 LAST PATH I18
J 0
(-1000 2225);
DISPLAY 0.978723 (-1000 2225);
PAINT WHITE (-1000 2225);
DISPLAY INVISIBLE (-1000 2225);
FORCEPROP 1 LAST PART_NUMBER CS00001JE10
J 0
(-1010 1925);
DISPLAY 0.978723 (-1010 1925);
DISPLAY INVISIBLE (-1010 1925);
FORCEADD PT5161LRS..5
(-2175 3825);
FORCEPROP 1 LAST LOCATION U6016
J 0
(-2525 6150);
DISPLAY 0.723404 (-2525 6150);
PAINT GREEN (-2525 6150);
FORCEPROP 0 LAST $SEC 5
J 0
(-2525 6300);
DISPLAY 0.680851 (-2525 6300);
PAINT MONO (-2525 6300);
DISPLAY INVISIBLE (-2525 6300);
FORCEPROP 0 LAST CDS_SEC 5
J 0
(-2525 6300);
DISPLAY 0.680851 (-2525 6300);
DISPLAY INVISIBLE (-2525 6300);
FORCEPROP 0 LASTPIN (-2675 5825) $PN AC13
J 2
(-2685 5835);
DISPLAY 0.680851 (-2685 5835);
PAINT MONO (-2685 5835);
FORCEPROP 0 LASTPIN (-2675 5775) $PN AC22
J 2
(-2685 5785);
DISPLAY 0.680851 (-2685 5785);
PAINT MONO (-2685 5785);
FORCEPROP 0 LASTPIN (-2675 5725) $PN AC32
J 2
(-2685 5735);
DISPLAY 0.680851 (-2685 5735);
PAINT MONO (-2685 5735);
FORCEPROP 0 LASTPIN (-2675 5675) $PN AC4
J 2
(-2685 5685);
DISPLAY 0.680851 (-2685 5685);
PAINT MONO (-2685 5685);
FORCEPROP 0 LASTPIN (-2675 5625) $PN AD2
J 2
(-2685 5635);
DISPLAY 0.680851 (-2685 5635);
PAINT MONO (-2685 5635);
FORCEPROP 0 LASTPIN (-2675 5575) $PN AD34
J 2
(-2685 5585);
DISPLAY 0.680851 (-2685 5585);
PAINT MONO (-2685 5585);
FORCEPROP 0 LASTPIN (-2675 5525) $PN AE1
J 2
(-2685 5535);
DISPLAY 0.680851 (-2685 5535);
PAINT MONO (-2685 5535);
FORCEPROP 0 LASTPIN (-2675 5475) $PN AE35
J 2
(-2685 5485);
DISPLAY 0.680851 (-2685 5485);
PAINT MONO (-2685 5485);
FORCEPROP 0 LASTPIN (-2675 5425) $PN AK13
J 2
(-2685 5435);
DISPLAY 0.680851 (-2685 5435);
PAINT MONO (-2685 5435);
FORCEPROP 0 LASTPIN (-2675 5375) $PN AK22
J 2
(-2685 5385);
DISPLAY 0.680851 (-2685 5385);
PAINT MONO (-2685 5385);
FORCEPROP 0 LASTPIN (-2675 5325) $PN AK32
J 2
(-2685 5335);
DISPLAY 0.680851 (-2685 5335);
PAINT MONO (-2685 5335);
FORCEPROP 0 LASTPIN (-2675 5275) $PN AK4
J 2
(-2685 5285);
DISPLAY 0.680851 (-2685 5285);
PAINT MONO (-2685 5285);
FORCEPROP 0 LASTPIN (-2675 5225) $PN AL2
J 2
(-2685 5235);
DISPLAY 0.680851 (-2685 5235);
PAINT MONO (-2685 5235);
FORCEPROP 0 LASTPIN (-2675 5175) $PN AL34
J 2
(-2685 5185);
DISPLAY 0.680851 (-2685 5185);
PAINT MONO (-2685 5185);
FORCEPROP 0 LASTPIN (-2675 5125) $PN AM1
J 2
(-2685 5135);
DISPLAY 0.680851 (-2685 5135);
PAINT MONO (-2685 5135);
FORCEPROP 0 LASTPIN (-2675 5075) $PN AM35
J 2
(-2685 5085);
DISPLAY 0.680851 (-2685 5085);
PAINT MONO (-2685 5085);
FORCEPROP 0 LASTPIN (-2675 5025) $PN AU13
J 2
(-2685 5035);
DISPLAY 0.680851 (-2685 5035);
PAINT MONO (-2685 5035);
FORCEPROP 0 LASTPIN (-2675 4975) $PN AU22
J 2
(-2685 4985);
DISPLAY 0.680851 (-2685 4985);
PAINT MONO (-2685 4985);
FORCEPROP 0 LASTPIN (-2675 4925) $PN AU32
J 2
(-2685 4935);
DISPLAY 0.680851 (-2685 4935);
PAINT MONO (-2685 4935);
FORCEPROP 0 LASTPIN (-2675 4875) $PN AU4
J 2
(-2685 4885);
DISPLAY 0.680851 (-2685 4885);
PAINT MONO (-2685 4885);
FORCEPROP 0 LASTPIN (-2675 4825) $PN AV2
J 2
(-2685 4835);
DISPLAY 0.680851 (-2685 4835);
PAINT MONO (-2685 4835);
FORCEPROP 0 LASTPIN (-2675 4775) $PN AV34
J 2
(-2685 4785);
DISPLAY 0.680851 (-2685 4785);
PAINT MONO (-2685 4785);
FORCEPROP 0 LASTPIN (-2675 4725) $PN AW1
J 2
(-2685 4735);
DISPLAY 0.680851 (-2685 4735);
PAINT MONO (-2685 4735);
FORCEPROP 0 LASTPIN (-2675 4675) $PN AW35
J 2
(-2685 4685);
DISPLAY 0.680851 (-2685 4685);
PAINT MONO (-2685 4685);
FORCEPROP 0 LASTPIN (-2675 4625) $PN B19
J 2
(-2685 4635);
DISPLAY 0.680851 (-2685 4635);
PAINT MONO (-2685 4635);
FORCEPROP 0 LASTPIN (-2675 4575) $PN BD13
J 2
(-2685 4585);
DISPLAY 0.680851 (-2685 4585);
PAINT MONO (-2685 4585);
FORCEPROP 0 LASTPIN (-2675 4525) $PN BD22
J 2
(-2685 4535);
DISPLAY 0.680851 (-2685 4535);
PAINT MONO (-2685 4535);
FORCEPROP 0 LASTPIN (-2675 4475) $PN BD32
J 2
(-2685 4485);
DISPLAY 0.680851 (-2685 4485);
PAINT MONO (-2685 4485);
FORCEPROP 0 LASTPIN (-2675 4425) $PN BD4
J 2
(-2685 4435);
DISPLAY 0.680851 (-2685 4435);
PAINT MONO (-2685 4435);
FORCEPROP 0 LASTPIN (-2675 4375) $PN BE2
J 2
(-2685 4385);
DISPLAY 0.680851 (-2685 4385);
PAINT MONO (-2685 4385);
FORCEPROP 0 LASTPIN (-2675 4325) $PN BE34
J 2
(-2685 4335);
DISPLAY 0.680851 (-2685 4335);
PAINT MONO (-2685 4335);
FORCEPROP 0 LASTPIN (-2675 4275) $PN BF1
J 2
(-2685 4285);
DISPLAY 0.680851 (-2685 4285);
PAINT MONO (-2685 4285);
FORCEPROP 0 LASTPIN (-2675 4225) $PN BF35
J 2
(-2685 4235);
DISPLAY 0.680851 (-2685 4235);
PAINT MONO (-2685 4235);
FORCEPROP 0 LASTPIN (-2675 4175) $PN BL13
J 2
(-2685 4185);
DISPLAY 0.680851 (-2685 4185);
PAINT MONO (-2685 4185);
FORCEPROP 0 LASTPIN (-2675 4125) $PN BL22
J 2
(-2685 4135);
DISPLAY 0.680851 (-2685 4135);
PAINT MONO (-2685 4135);
FORCEPROP 0 LASTPIN (-2675 4075) $PN BL32
J 2
(-2685 4085);
DISPLAY 0.680851 (-2685 4085);
PAINT MONO (-2685 4085);
FORCEPROP 0 LASTPIN (-2675 4025) $PN BL4
J 2
(-2685 4035);
DISPLAY 0.680851 (-2685 4035);
PAINT MONO (-2685 4035);
FORCEPROP 0 LASTPIN (-2675 3975) $PN BM2
J 2
(-2685 3985);
DISPLAY 0.680851 (-2685 3985);
PAINT MONO (-2685 3985);
FORCEPROP 0 LASTPIN (-2675 3925) $PN BM34
J 2
(-2685 3935);
DISPLAY 0.680851 (-2685 3935);
PAINT MONO (-2685 3935);
FORCEPROP 0 LASTPIN (-2675 3875) $PN BN1
J 2
(-2685 3885);
DISPLAY 0.680851 (-2685 3885);
PAINT MONO (-2685 3885);
FORCEPROP 0 LASTPIN (-2675 3825) $PN BN35
J 2
(-2685 3835);
DISPLAY 0.680851 (-2685 3835);
PAINT MONO (-2685 3835);
FORCEPROP 0 LASTPIN (-2675 3775) $PN BV13
J 2
(-2685 3785);
DISPLAY 0.680851 (-2685 3785);
PAINT MONO (-2685 3785);
FORCEPROP 0 LASTPIN (-2675 3725) $PN BV22
J 2
(-2685 3735);
DISPLAY 0.680851 (-2685 3735);
PAINT MONO (-2685 3735);
FORCEPROP 0 LASTPIN (-2675 3675) $PN BV32
J 2
(-2685 3685);
DISPLAY 0.680851 (-2685 3685);
PAINT MONO (-2685 3685);
FORCEPROP 0 LASTPIN (-2675 3625) $PN BV4
J 2
(-2685 3635);
DISPLAY 0.680851 (-2685 3635);
PAINT MONO (-2685 3635);
FORCEPROP 0 LASTPIN (-2675 3575) $PN BW2
J 2
(-2685 3585);
DISPLAY 0.680851 (-2685 3585);
PAINT MONO (-2685 3585);
FORCEPROP 0 LASTPIN (-2675 3525) $PN BW34
J 2
(-2685 3535);
DISPLAY 0.680851 (-2685 3535);
PAINT MONO (-2685 3535);
FORCEPROP 0 LASTPIN (-2675 3475) $PN BY1
J 2
(-2685 3485);
DISPLAY 0.680851 (-2685 3485);
PAINT MONO (-2685 3485);
FORCEPROP 0 LASTPIN (-2675 3425) $PN BY35
J 2
(-2685 3435);
DISPLAY 0.680851 (-2685 3435);
PAINT MONO (-2685 3435);
FORCEPROP 0 LASTPIN (-2675 3375) $PN CE13
J 2
(-2685 3385);
DISPLAY 0.680851 (-2685 3385);
PAINT MONO (-2685 3385);
FORCEPROP 0 LASTPIN (-2675 3325) $PN CE22
J 2
(-2685 3335);
DISPLAY 0.680851 (-2685 3335);
PAINT MONO (-2685 3335);
FORCEPROP 0 LASTPIN (-2675 3275) $PN CE32
J 2
(-2685 3285);
DISPLAY 0.680851 (-2685 3285);
PAINT MONO (-2685 3285);
FORCEPROP 0 LASTPIN (-2675 3225) $PN CE4
J 2
(-2685 3235);
DISPLAY 0.680851 (-2685 3235);
PAINT MONO (-2685 3235);
FORCEPROP 0 LASTPIN (-2675 3175) $PN CF2
J 2
(-2685 3185);
DISPLAY 0.680851 (-2685 3185);
PAINT MONO (-2685 3185);
FORCEPROP 0 LASTPIN (-2675 3125) $PN CF34
J 2
(-2685 3135);
DISPLAY 0.680851 (-2685 3135);
PAINT MONO (-2685 3135);
FORCEPROP 0 LASTPIN (-2675 3075) $PN CG1
J 2
(-2685 3085);
DISPLAY 0.680851 (-2685 3085);
PAINT MONO (-2685 3085);
FORCEPROP 0 LASTPIN (-2675 3025) $PN CG35
J 2
(-2685 3035);
DISPLAY 0.680851 (-2685 3035);
PAINT MONO (-2685 3035);
FORCEPROP 0 LASTPIN (-2675 2975) $PN CM13
J 2
(-2685 2985);
DISPLAY 0.680851 (-2685 2985);
PAINT MONO (-2685 2985);
FORCEPROP 0 LASTPIN (-2675 2925) $PN CM22
J 2
(-2685 2935);
DISPLAY 0.680851 (-2685 2935);
PAINT MONO (-2685 2935);
FORCEPROP 0 LASTPIN (-2675 2875) $PN CM32
J 2
(-2685 2885);
DISPLAY 0.680851 (-2685 2885);
PAINT MONO (-2685 2885);
FORCEPROP 0 LASTPIN (-2675 2825) $PN CM4
J 2
(-2685 2835);
DISPLAY 0.680851 (-2685 2835);
PAINT MONO (-2685 2835);
FORCEPROP 0 LASTPIN (-2675 2775) $PN CN2
J 2
(-2685 2785);
DISPLAY 0.680851 (-2685 2785);
PAINT MONO (-2685 2785);
FORCEPROP 0 LASTPIN (-2675 2725) $PN CN34
J 2
(-2685 2735);
DISPLAY 0.680851 (-2685 2735);
PAINT MONO (-2685 2735);
FORCEPROP 0 LASTPIN (-2675 2675) $PN CP1
J 2
(-2685 2685);
DISPLAY 0.680851 (-2685 2685);
PAINT MONO (-2685 2685);
FORCEPROP 0 LASTPIN (-2675 2625) $PN CP35
J 2
(-2685 2635);
DISPLAY 0.680851 (-2685 2635);
PAINT MONO (-2685 2635);
FORCEPROP 0 LASTPIN (-2675 2575) $PN CW13
J 2
(-2685 2585);
DISPLAY 0.680851 (-2685 2585);
PAINT MONO (-2685 2585);
FORCEPROP 0 LASTPIN (-2675 2525) $PN CW22
J 2
(-2685 2535);
DISPLAY 0.680851 (-2685 2535);
PAINT MONO (-2685 2535);
FORCEPROP 0 LASTPIN (-2675 2475) $PN CW32
J 2
(-2685 2485);
DISPLAY 0.680851 (-2685 2485);
PAINT MONO (-2685 2485);
FORCEPROP 0 LASTPIN (-2675 2425) $PN CW4
J 2
(-2685 2435);
DISPLAY 0.680851 (-2685 2435);
PAINT MONO (-2685 2435);
FORCEPROP 0 LASTPIN (-2675 2375) $PN CY2
J 2
(-2685 2385);
DISPLAY 0.680851 (-2685 2385);
PAINT MONO (-2685 2385);
FORCEPROP 0 LASTPIN (-2675 2325) $PN CY34
J 2
(-2685 2335);
DISPLAY 0.680851 (-2685 2335);
PAINT MONO (-2685 2335);
FORCEPROP 0 LASTPIN (-2675 2275) $PN DA1
J 2
(-2685 2285);
DISPLAY 0.680851 (-2685 2285);
PAINT MONO (-2685 2285);
FORCEPROP 0 LASTPIN (-2675 2225) $PN DA35
J 2
(-2685 2235);
DISPLAY 0.680851 (-2685 2235);
PAINT MONO (-2685 2235);
FORCEPROP 0 LASTPIN (-2675 2175) $PN DF13
J 2
(-2685 2185);
DISPLAY 0.680851 (-2685 2185);
PAINT MONO (-2685 2185);
FORCEPROP 0 LASTPIN (-2675 2125) $PN DF22
J 2
(-2685 2135);
DISPLAY 0.680851 (-2685 2135);
PAINT MONO (-2685 2135);
FORCEPROP 0 LASTPIN (-2675 2075) $PN DF32
J 2
(-2685 2085);
DISPLAY 0.680851 (-2685 2085);
PAINT MONO (-2685 2085);
FORCEPROP 0 LASTPIN (-2675 2025) $PN DF4
J 2
(-2685 2035);
DISPLAY 0.680851 (-2685 2035);
PAINT MONO (-2685 2035);
FORCEPROP 0 LASTPIN (-2675 1975) $PN DG2
J 2
(-2685 1985);
DISPLAY 0.680851 (-2685 1985);
PAINT MONO (-2685 1985);
FORCEPROP 0 LASTPIN (-2675 1925) $PN DG34
J 2
(-2685 1935);
DISPLAY 0.680851 (-2685 1935);
PAINT MONO (-2685 1935);
FORCEPROP 0 LASTPIN (-2675 1875) $PN DH1
J 2
(-2685 1885);
DISPLAY 0.680851 (-2685 1885);
PAINT MONO (-2685 1885);
FORCEPROP 0 LASTPIN (-2675 1825) $PN DH35
J 2
(-2685 1835);
DISPLAY 0.680851 (-2685 1835);
PAINT MONO (-2685 1835);
FORCEPROP 0 LASTPIN (-2675 1775) $PN DN13
J 2
(-2685 1785);
DISPLAY 0.680851 (-2685 1785);
PAINT MONO (-2685 1785);
FORCEPROP 0 LASTPIN (-1725 5825) $PN DN22
J 0
(-1715 5835);
DISPLAY 0.680851 (-1715 5835);
PAINT MONO (-1715 5835);
FORCEPROP 0 LASTPIN (-1725 5775) $PN DN32
J 0
(-1715 5785);
DISPLAY 0.680851 (-1715 5785);
PAINT MONO (-1715 5785);
FORCEPROP 0 LASTPIN (-1725 5725) $PN DN4
J 0
(-1715 5735);
DISPLAY 0.680851 (-1715 5735);
PAINT MONO (-1715 5735);
FORCEPROP 0 LASTPIN (-1725 5675) $PN DP2
J 0
(-1715 5685);
DISPLAY 0.680851 (-1715 5685);
PAINT MONO (-1715 5685);
FORCEPROP 0 LASTPIN (-1725 5625) $PN DP34
J 0
(-1715 5635);
DISPLAY 0.680851 (-1715 5635);
PAINT MONO (-1715 5635);
FORCEPROP 0 LASTPIN (-1725 5575) $PN DR1
J 0
(-1715 5585);
DISPLAY 0.680851 (-1715 5585);
PAINT MONO (-1715 5585);
FORCEPROP 0 LASTPIN (-1725 5525) $PN DR35
J 0
(-1715 5535);
DISPLAY 0.680851 (-1715 5535);
PAINT MONO (-1715 5535);
FORCEPROP 0 LASTPIN (-1725 5475) $PN DY13
J 0
(-1715 5485);
DISPLAY 0.680851 (-1715 5485);
PAINT MONO (-1715 5485);
FORCEPROP 0 LASTPIN (-1725 5425) $PN DY22
J 0
(-1715 5435);
DISPLAY 0.680851 (-1715 5435);
PAINT MONO (-1715 5435);
FORCEPROP 0 LASTPIN (-1725 5375) $PN DY32
J 0
(-1715 5385);
DISPLAY 0.680851 (-1715 5385);
PAINT MONO (-1715 5385);
FORCEPROP 0 LASTPIN (-1725 5325) $PN DY4
J 0
(-1715 5335);
DISPLAY 0.680851 (-1715 5335);
PAINT MONO (-1715 5335);
FORCEPROP 0 LASTPIN (-1725 5275) $PN E14
J 0
(-1715 5285);
DISPLAY 0.680851 (-1715 5285);
PAINT MONO (-1715 5285);
FORCEPROP 0 LASTPIN (-1725 5225) $PN E27
J 0
(-1715 5235);
DISPLAY 0.680851 (-1715 5235);
PAINT MONO (-1715 5235);
FORCEPROP 0 LASTPIN (-1725 5175) $PN E33
J 0
(-1715 5185);
DISPLAY 0.680851 (-1715 5185);
PAINT MONO (-1715 5185);
FORCEPROP 0 LASTPIN (-1725 5125) $PN EA2
J 0
(-1715 5135);
DISPLAY 0.680851 (-1715 5135);
PAINT MONO (-1715 5135);
FORCEPROP 0 LASTPIN (-1725 5075) $PN EA34
J 0
(-1715 5085);
DISPLAY 0.680851 (-1715 5085);
PAINT MONO (-1715 5085);
FORCEPROP 0 LASTPIN (-1725 5025) $PN EB1
J 0
(-1715 5035);
DISPLAY 0.680851 (-1715 5035);
PAINT MONO (-1715 5035);
FORCEPROP 0 LASTPIN (-1725 4975) $PN EB35
J 0
(-1715 4985);
DISPLAY 0.680851 (-1715 4985);
PAINT MONO (-1715 4985);
FORCEPROP 0 LASTPIN (-1725 4925) $PN EG13
J 0
(-1715 4935);
DISPLAY 0.680851 (-1715 4935);
PAINT MONO (-1715 4935);
FORCEPROP 0 LASTPIN (-1725 4875) $PN EG22
J 0
(-1715 4885);
DISPLAY 0.680851 (-1715 4885);
PAINT MONO (-1715 4885);
FORCEPROP 0 LASTPIN (-1725 4825) $PN EG32
J 0
(-1715 4835);
DISPLAY 0.680851 (-1715 4835);
PAINT MONO (-1715 4835);
FORCEPROP 0 LASTPIN (-1725 4775) $PN EG4
J 0
(-1715 4785);
DISPLAY 0.680851 (-1715 4785);
PAINT MONO (-1715 4785);
FORCEPROP 0 LASTPIN (-1725 4725) $PN EH2
J 0
(-1715 4735);
DISPLAY 0.680851 (-1715 4735);
PAINT MONO (-1715 4735);
FORCEPROP 0 LASTPIN (-1725 4675) $PN EH34
J 0
(-1715 4685);
DISPLAY 0.680851 (-1715 4685);
PAINT MONO (-1715 4685);
FORCEPROP 0 LASTPIN (-1725 4625) $PN EJ1
J 0
(-1715 4635);
DISPLAY 0.680851 (-1715 4635);
PAINT MONO (-1715 4635);
FORCEPROP 0 LASTPIN (-1725 4575) $PN EJ35
J 0
(-1715 4585);
DISPLAY 0.680851 (-1715 4585);
PAINT MONO (-1715 4585);
FORCEPROP 0 LASTPIN (-1725 4525) $PN EP13
J 0
(-1715 4535);
DISPLAY 0.680851 (-1715 4535);
PAINT MONO (-1715 4535);
FORCEPROP 0 LASTPIN (-1725 4475) $PN EP22
J 0
(-1715 4485);
DISPLAY 0.680851 (-1715 4485);
PAINT MONO (-1715 4485);
FORCEPROP 0 LASTPIN (-1725 4425) $PN EP32
J 0
(-1715 4435);
DISPLAY 0.680851 (-1715 4435);
PAINT MONO (-1715 4435);
FORCEPROP 0 LASTPIN (-1725 4375) $PN EP4
J 0
(-1715 4385);
DISPLAY 0.680851 (-1715 4385);
PAINT MONO (-1715 4385);
FORCEPROP 0 LASTPIN (-1725 4325) $PN ER2
J 0
(-1715 4335);
DISPLAY 0.680851 (-1715 4335);
PAINT MONO (-1715 4335);
FORCEPROP 0 LASTPIN (-1725 4275) $PN ER34
J 0
(-1715 4285);
DISPLAY 0.680851 (-1715 4285);
PAINT MONO (-1715 4285);
FORCEPROP 0 LASTPIN (-1725 4225) $PN ET1
J 0
(-1715 4235);
DISPLAY 0.680851 (-1715 4235);
PAINT MONO (-1715 4235);
FORCEPROP 0 LASTPIN (-1725 4175) $PN ET35
J 0
(-1715 4185);
DISPLAY 0.680851 (-1715 4185);
PAINT MONO (-1715 4185);
FORCEPROP 0 LASTPIN (-1725 4125) $PN FA15
J 0
(-1715 4135);
DISPLAY 0.680851 (-1715 4135);
PAINT MONO (-1715 4135);
FORCEPROP 0 LASTPIN (-1725 4075) $PN FA32
J 0
(-1715 4085);
DISPLAY 0.680851 (-1715 4085);
PAINT MONO (-1715 4085);
FORCEPROP 0 LASTPIN (-1725 4025) $PN FB2
J 0
(-1715 4035);
DISPLAY 0.680851 (-1715 4035);
PAINT MONO (-1715 4035);
FORCEPROP 0 LASTPIN (-1725 3975) $PN FB34
J 0
(-1715 3985);
DISPLAY 0.680851 (-1715 3985);
PAINT MONO (-1715 3985);
FORCEPROP 0 LASTPIN (-1725 3925) $PN FC19
J 0
(-1715 3935);
DISPLAY 0.680851 (-1715 3935);
PAINT MONO (-1715 3935);
FORCEPROP 0 LASTPIN (-1725 3875) $PN FC23
J 0
(-1715 3885);
DISPLAY 0.680851 (-1715 3885);
PAINT MONO (-1715 3885);
FORCEPROP 0 LASTPIN (-1725 3825) $PN FC25
J 0
(-1715 3835);
DISPLAY 0.680851 (-1715 3835);
PAINT MONO (-1715 3835);
FORCEPROP 0 LASTPIN (-1725 3775) $PN FC28
J 0
(-1715 3785);
DISPLAY 0.680851 (-1715 3785);
PAINT MONO (-1715 3785);
FORCEPROP 0 LASTPIN (-1725 3725) $PN FC3
J 0
(-1715 3735);
DISPLAY 0.680851 (-1715 3735);
PAINT MONO (-1715 3735);
FORCEPROP 0 LASTPIN (-1725 3675) $PN FC6
J 0
(-1715 3685);
DISPLAY 0.680851 (-1715 3685);
PAINT MONO (-1715 3685);
FORCEPROP 0 LASTPIN (-1725 3625) $PN FC9
J 0
(-1715 3635);
DISPLAY 0.680851 (-1715 3635);
PAINT MONO (-1715 3635);
FORCEPROP 0 LASTPIN (-1725 3575) $PN FD1
J 0
(-1715 3585);
DISPLAY 0.680851 (-1715 3585);
PAINT MONO (-1715 3585);
FORCEPROP 0 LASTPIN (-1725 3525) $PN FD35
J 0
(-1715 3535);
DISPLAY 0.680851 (-1715 3535);
PAINT MONO (-1715 3535);
FORCEPROP 0 LASTPIN (-1725 3475) $PN FF14
J 0
(-1715 3485);
DISPLAY 0.680851 (-1715 3485);
PAINT MONO (-1715 3485);
FORCEPROP 0 LASTPIN (-1725 3425) $PN FF21
J 0
(-1715 3435);
DISPLAY 0.680851 (-1715 3435);
PAINT MONO (-1715 3435);
FORCEPROP 0 LASTPIN (-1725 3375) $PN FJ12
J 0
(-1715 3385);
DISPLAY 0.680851 (-1715 3385);
PAINT MONO (-1715 3385);
FORCEPROP 0 LASTPIN (-1725 3325) $PN FJ19
J 0
(-1715 3335);
DISPLAY 0.680851 (-1715 3335);
PAINT MONO (-1715 3335);
FORCEPROP 0 LASTPIN (-1725 3275) $PN H12
J 0
(-1715 3285);
DISPLAY 0.680851 (-1715 3285);
PAINT MONO (-1715 3285);
FORCEPROP 0 LASTPIN (-1725 3225) $PN H16
J 0
(-1715 3235);
DISPLAY 0.680851 (-1715 3235);
PAINT MONO (-1715 3235);
FORCEPROP 0 LASTPIN (-1725 3175) $PN H19
J 0
(-1715 3185);
DISPLAY 0.680851 (-1715 3185);
PAINT MONO (-1715 3185);
FORCEPROP 0 LASTPIN (-1725 3125) $PN H31
J 0
(-1715 3135);
DISPLAY 0.680851 (-1715 3135);
PAINT MONO (-1715 3135);
FORCEPROP 0 LASTPIN (-1725 3075) $PN J22
J 0
(-1715 3085);
DISPLAY 0.680851 (-1715 3085);
PAINT MONO (-1715 3085);
FORCEPROP 0 LASTPIN (-1725 3025) $PN J4
J 0
(-1715 3035);
DISPLAY 0.680851 (-1715 3035);
PAINT MONO (-1715 3035);
FORCEPROP 0 LASTPIN (-1725 2975) $PN K2
J 0
(-1715 2985);
DISPLAY 0.680851 (-1715 2985);
PAINT MONO (-1715 2985);
FORCEPROP 0 LASTPIN (-1725 2925) $PN K34
J 0
(-1715 2935);
DISPLAY 0.680851 (-1715 2935);
PAINT MONO (-1715 2935);
FORCEPROP 0 LASTPIN (-1725 2875) $PN L1
J 0
(-1715 2885);
DISPLAY 0.680851 (-1715 2885);
PAINT MONO (-1715 2885);
FORCEPROP 0 LASTPIN (-1725 2825) $PN L35
J 0
(-1715 2835);
DISPLAY 0.680851 (-1715 2835);
PAINT MONO (-1715 2835);
FORCEPROP 0 LASTPIN (-1725 2775) $PN T13
J 0
(-1715 2785);
DISPLAY 0.680851 (-1715 2785);
PAINT MONO (-1715 2785);
FORCEPROP 0 LASTPIN (-1725 2725) $PN T22
J 0
(-1715 2735);
DISPLAY 0.680851 (-1715 2735);
PAINT MONO (-1715 2735);
FORCEPROP 0 LASTPIN (-1725 2675) $PN T32
J 0
(-1715 2685);
DISPLAY 0.680851 (-1715 2685);
PAINT MONO (-1715 2685);
FORCEPROP 0 LASTPIN (-1725 2625) $PN T4
J 0
(-1715 2635);
DISPLAY 0.680851 (-1715 2635);
PAINT MONO (-1715 2635);
FORCEPROP 0 LASTPIN (-1725 2575) $PN U2
J 0
(-1715 2585);
DISPLAY 0.680851 (-1715 2585);
PAINT MONO (-1715 2585);
FORCEPROP 0 LASTPIN (-1725 2525) $PN U34
J 0
(-1715 2535);
DISPLAY 0.680851 (-1715 2535);
PAINT MONO (-1715 2535);
FORCEPROP 0 LASTPIN (-1725 2475) $PN V1
J 0
(-1715 2485);
DISPLAY 0.680851 (-1715 2485);
PAINT MONO (-1715 2485);
FORCEPROP 0 LASTPIN (-1725 2425) $PN V35
J 0
(-1715 2435);
DISPLAY 0.680851 (-1715 2435);
PAINT MONO (-1715 2435);
FORCEPROP 0 LASTPIN (-1725 2325) $PN A1
J 0
(-1715 2335);
DISPLAY 0.680851 (-1715 2335);
PAINT MONO (-1715 2335);
FORCEPROP 0 LASTPIN (-1725 2275) $PN A35
J 0
(-1715 2285);
DISPLAY 0.680851 (-1715 2285);
PAINT MONO (-1715 2285);
FORCEPROP 0 LASTPIN (-1725 2225) $PN C2
J 0
(-1715 2235);
DISPLAY 0.680851 (-1715 2235);
PAINT MONO (-1715 2235);
FORCEPROP 0 LASTPIN (-1725 2175) $PN C34
J 0
(-1715 2185);
DISPLAY 0.680851 (-1715 2185);
PAINT MONO (-1715 2185);
FORCEPROP 0 LASTPIN (-1725 2125) $PN D1
J 0
(-1715 2135);
DISPLAY 0.680851 (-1715 2135);
PAINT MONO (-1715 2135);
FORCEPROP 0 LASTPIN (-1725 2075) $PN D35
J 0
(-1715 2085);
DISPLAY 0.680851 (-1715 2085);
PAINT MONO (-1715 2085);
FORCEPROP 0 LASTPIN (-1725 2025) $PN FE2
J 0
(-1715 2035);
DISPLAY 0.680851 (-1715 2035);
PAINT MONO (-1715 2035);
FORCEPROP 0 LASTPIN (-1725 1975) $PN FE34
J 0
(-1715 1985);
DISPLAY 0.680851 (-1715 1985);
PAINT MONO (-1715 1985);
FORCEPROP 0 LASTPIN (-1725 1925) $PN FG1
J 0
(-1715 1935);
DISPLAY 0.680851 (-1715 1935);
PAINT MONO (-1715 1935);
FORCEPROP 0 LASTPIN (-1725 1875) $PN FG35
J 0
(-1715 1885);
DISPLAY 0.680851 (-1715 1885);
PAINT MONO (-1715 1885);
FORCEPROP 0 LASTPIN (-1725 1825) $PN FH2
J 0
(-1715 1835);
DISPLAY 0.680851 (-1715 1835);
PAINT MONO (-1715 1835);
FORCEPROP 0 LASTPIN (-1725 1775) $PN FH34
J 0
(-1715 1785);
DISPLAY 0.680851 (-1715 1785);
PAINT MONO (-1715 1785);
FORCEPROP 2 LAST PART_TYPE SMLF
J 0
(-2525 6250);
DISPLAY 0.680851 (-2525 6250);
FORCEPROP 2 LAST VALUE PT5161LRS
J 0
(-2525 6200);
DISPLAY 0.680851 (-2525 6200);
FORCEPROP 1 LAST MATERIAL IC
J 0
(-2525 6000);
DISPLAY 0.723404 (-2525 6000);
PAINT GREEN (-2525 6000);
FORCEPROP 1 LAST NEEDS_NO_SIZE TRUE
J 0
(-2175 3825);
DISPLAY 0.723404 (-2175 3825);
PAINT GREEN (-2175 3825);
DISPLAY INVISIBLE (-2175 3825);
FORCEPROP 1 LAST CDS_LMAN_SYM_OUTLINE -350,2150,300,-2150
J 0
(-2175 3825);
DISPLAY 0.468085 (-2175 3825);
PAINT GREEN (-2175 3825);
DISPLAY INVISIBLE (-2175 3825);
FORCEPROP 2 LAST CDS_LIB pure_quanta
J 0
(-2175 3825);
DISPLAY INVISIBLE (-2175 3825);
FORCEPROP 1 LAST PATH I19
J 0
(-2175 3825);
DISPLAY 0.723404 (-2175 3825);
PAINT GREEN (-2175 3825);
DISPLAY INVISIBLE (-2175 3825);
FORCEPROP 1 LAST PART_NUMBER AJ051610U03
J 0
(-2525 6075);
DISPLAY 0.723404 (-2525 6075);
PAINT GREEN (-2525 6075);
DISPLAY INVISIBLE (-2525 6075);
FORCEADD Q_RES..2
(-7400 3600);
FORCEPROP 1 LAST LOCATION R6795
J 0
(-7355 3725);
DISPLAY 0.978723 (-7355 3725);
PAINT WHITE (-7355 3725);
FORCEPROP 0 LAST $SEC 1
J 0
(-7350 3775);
DISPLAY 0.680851 (-7350 3775);
PAINT MONO (-7350 3775);
DISPLAY INVISIBLE (-7350 3775);
FORCEPROP 0 LAST CDS_SEC 1
J 0
(-7350 3775);
DISPLAY 0.680851 (-7350 3775);
DISPLAY INVISIBLE (-7350 3775);
FORCEPROP 1 LASTPIN (-7400 3700) $PN 1
J 0
(-7395 3662);
DISPLAY 0.787234 (-7395 3662);
PAINT MONO (-7395 3662);
FORCEPROP 1 LASTPIN (-7400 3500) $PN 2
J 0
(-7395 3510);
DISPLAY 0.787234 (-7395 3510);
PAINT MONO (-7395 3510);
FORCEPROP 1 LAST PACK_TYPE 0201LF
J 0
(-7360 3425);
DISPLAY 0.978723 (-7360 3425);
FORCEPROP 1 LAST TOLERANCE 1%
J 0
(-7355 3625);
DISPLAY 0.978723 (-7355 3625);
FORCEPROP 1 LAST VALUE 200
J 0
(-7355 3675);
DISPLAY 0.978723 (-7355 3675);
FORCEPROP 1 LAST WATTAGE 1/20W
J 0
(-7360 3575);
DISPLAY 0.978723 (-7360 3575);
FORCEPROP 1 LAST MATERIAL CHIP
J 0
(-7360 3525);
DISPLAY 0.978723 (-7360 3525);
FORCEPROP 2 LAST CDS_LIB pure_quanta
J 0
(-7400 3600);
DISPLAY INVISIBLE (-7400 3600);
FORCEPROP 1 LAST PATH I20
J 0
(-7350 3775);
DISPLAY 0.978723 (-7350 3775);
PAINT WHITE (-7350 3775);
DISPLAY INVISIBLE (-7350 3775);
FORCEPROP 1 LAST PART_NUMBER CS12001FE12
J 0
(-7360 3475);
DISPLAY 0.978723 (-7360 3475);
DISPLAY INVISIBLE (-7360 3475);
FORCEADD Q_RES..2
(-8425 4150);
FORCEPROP 1 LAST LOCATION R6794
J 0
(-8380 4275);
DISPLAY 0.787234 (-8380 4275);
PAINT SKYBLUE (-8380 4275);
FORCEPROP 0 LAST $SEC 1
J 0
(-8375 4325);
DISPLAY 0.680851 (-8375 4325);
PAINT MONO (-8375 4325);
DISPLAY INVISIBLE (-8375 4325);
FORCEPROP 0 LAST CDS_SEC 1
J 0
(-8375 4325);
DISPLAY 0.680851 (-8375 4325);
DISPLAY INVISIBLE (-8375 4325);
FORCEPROP 1 LASTPIN (-8425 4250) $PN 1
J 0
(-8420 4212);
DISPLAY 0.787234 (-8420 4212);
PAINT MONO (-8420 4212);
FORCEPROP 1 LASTPIN (-8425 4050) $PN 2
J 0
(-8420 4060);
DISPLAY 0.787234 (-8420 4060);
PAINT MONO (-8420 4060);
FORCEPROP 1 LAST MATERIAL EMPTY
J 0
(-8385 4075);
DISPLAY 0.787234 (-8385 4075);
PAINT RED (-8385 4075);
FORCEPROP 1 LAST VALUE 1K
J 0
(-8380 4225);
DISPLAY 0.787234 (-8380 4225);
FORCEPROP 1 LAST TOLERANCE 1%
J 0
(-8380 4175);
DISPLAY 0.787234 (-8380 4175);
FORCEPROP 1 LAST WATTAGE 1/20W
J 0
(-8385 4125);
DISPLAY 0.787234 (-8385 4125);
FORCEPROP 1 LAST PACK_TYPE 0201LF
J 0
(-8385 3975);
DISPLAY 0.787234 (-8385 3975);
FORCEPROP 2 LAST CDS_LIB pure_quanta
J 0
(-8425 4150);
DISPLAY INVISIBLE (-8425 4150);
FORCEPROP 1 LAST PATH I21
J 0
(-8375 4325);
DISPLAY 0.978723 (-8375 4325);
PAINT WHITE (-8375 4325);
DISPLAY INVISIBLE (-8375 4325);
FORCEPROP 1 LAST PART_NUMBER CS21001FE07
J 0
(-8385 4025);
DISPLAY 0.978723 (-8385 4025);
DISPLAY INVISIBLE (-8385 4025);
FORCEADD P1V0..1
(-8425 4375);
FORCEPROP 3 LASTPIN (-8425 4325) SIG_NAME P1V8_CPU1_RT_1D\g
J 0
(-8415 4335);
DISPLAY 0.659574 (-8415 4335);
PAINT MONO (-8415 4335);
DISPLAY INVISIBLE (-8415 4335);
FORCEPROP 1 LAST HDL_POWER P1V8_CPU1_RT_1D
J 1
(-8425 4425);
DISPLAY 0.489362 (-8425 4425);
PAINT SKYBLUE (-8425 4425);
FORCEPROP 2 LAST CDS_LIB pure_quanta_power
J 0
(-8425 4375);
DISPLAY INVISIBLE (-8425 4375);
FORCEPROP 1 LAST PATH I4
J 0
(-8375 4400);
DISPLAY 0.872340 (-8375 4400);
PAINT AQUA (-8375 4400);
DISPLAY INVISIBLE (-8375 4400);
FORCEADD UNIVERSAL_GND..1
(-7400 3350);
FORCEPROP 3 LASTPIN (-7400 3400) SIG_NAME GND\g
J 0
(-7390 3410);
DISPLAY 0.659574 (-7390 3410);
PAINT MONO (-7390 3410);
DISPLAY INVISIBLE (-7390 3410);
FORCEPROP 2 LAST CDS_LIB pure_quanta_power
J 0
(-7400 3350);
DISPLAY INVISIBLE (-7400 3350);
FORCEPROP 1 LAST HDL_POWER GND
J 1
(-7375 3275);
DISPLAY 0.872340 (-7375 3275);
PAINT GREEN (-7375 3275);
DISPLAY INVISIBLE (-7375 3275);
FORCEPROP 1 LAST PATH I5
J 0
(-7325 3350);
DISPLAY 0.872340 (-7325 3350);
PAINT AQUA (-7325 3350);
DISPLAY INVISIBLE (-7325 3350);
FORCEADD PT5161LRS..4
(-6250 4400);
FORCEPROP 1 LAST LOCATION U6016
J 0
(-6700 5325);
DISPLAY 0.723404 (-6700 5325);
PAINT GREEN (-6700 5325);
FORCEPROP 0 LAST $SEC 4
J 0
(-6700 5475);
DISPLAY 0.680851 (-6700 5475);
PAINT MONO (-6700 5475);
DISPLAY INVISIBLE (-6700 5475);
FORCEPROP 0 LAST CDS_SEC 4
J 0
(-6700 5475);
DISPLAY 0.680851 (-6700 5475);
DISPLAY INVISIBLE (-6700 5475);
FORCEPROP 0 LASTPIN (-6850 5000) $PN BV20
J 2
(-6860 5010);
DISPLAY 0.680851 (-6860 5010);
PAINT MONO (-6860 5010);
FORCEPROP 0 LASTPIN (-6850 4950) $PN CE17
J 2
(-6860 4960);
DISPLAY 0.680851 (-6860 4960);
PAINT MONO (-6860 4960);
FORCEPROP 0 LASTPIN (-6850 4900) $PN CE20
J 2
(-6860 4910);
DISPLAY 0.680851 (-6860 4910);
PAINT MONO (-6860 4910);
FORCEPROP 0 LASTPIN (-6850 4850) $PN CM17
J 2
(-6860 4860);
DISPLAY 0.680851 (-6860 4860);
PAINT MONO (-6860 4860);
FORCEPROP 0 LASTPIN (-6850 4800) $PN CM20
J 2
(-6860 4810);
DISPLAY 0.680851 (-6860 4810);
PAINT MONO (-6860 4810);
FORCEPROP 0 LASTPIN (-6850 4350) $PN BV17
J 2
(-6860 4360);
DISPLAY 0.680851 (-6860 4360);
PAINT MONO (-6860 4360);
FORCEPROP 0 LASTPIN (-5700 5000) $PN AC17
J 0
(-5690 5010);
DISPLAY 0.680851 (-5690 5010);
PAINT MONO (-5690 5010);
FORCEPROP 0 LASTPIN (-5700 4950) $PN AC20
J 0
(-5690 4960);
DISPLAY 0.680851 (-5690 4960);
PAINT MONO (-5690 4960);
FORCEPROP 0 LASTPIN (-5700 4900) $PN AK17
J 0
(-5690 4910);
DISPLAY 0.680851 (-5690 4910);
PAINT MONO (-5690 4910);
FORCEPROP 0 LASTPIN (-5700 4850) $PN AK20
J 0
(-5690 4860);
DISPLAY 0.680851 (-5690 4860);
PAINT MONO (-5690 4860);
FORCEPROP 0 LASTPIN (-5700 4800) $PN AU17
J 0
(-5690 4810);
DISPLAY 0.680851 (-5690 4810);
PAINT MONO (-5690 4810);
FORCEPROP 0 LASTPIN (-5700 4750) $PN AU20
J 0
(-5690 4760);
DISPLAY 0.680851 (-5690 4760);
PAINT MONO (-5690 4760);
FORCEPROP 0 LASTPIN (-5700 4700) $PN BD17
J 0
(-5690 4710);
DISPLAY 0.680851 (-5690 4710);
PAINT MONO (-5690 4710);
FORCEPROP 0 LASTPIN (-5700 4650) $PN BD20
J 0
(-5690 4660);
DISPLAY 0.680851 (-5690 4660);
PAINT MONO (-5690 4660);
FORCEPROP 0 LASTPIN (-5700 4600) $PN DF17
J 0
(-5690 4610);
DISPLAY 0.680851 (-5690 4610);
PAINT MONO (-5690 4610);
FORCEPROP 0 LASTPIN (-5700 4550) $PN DF20
J 0
(-5690 4560);
DISPLAY 0.680851 (-5690 4560);
PAINT MONO (-5690 4560);
FORCEPROP 0 LASTPIN (-5700 4500) $PN DN17
J 0
(-5690 4510);
DISPLAY 0.680851 (-5690 4510);
PAINT MONO (-5690 4510);
FORCEPROP 0 LASTPIN (-5700 4450) $PN DN20
J 0
(-5690 4460);
DISPLAY 0.680851 (-5690 4460);
PAINT MONO (-5690 4460);
FORCEPROP 0 LASTPIN (-5700 4400) $PN DY17
J 0
(-5690 4410);
DISPLAY 0.680851 (-5690 4410);
PAINT MONO (-5690 4410);
FORCEPROP 0 LASTPIN (-5700 4350) $PN DY20
J 0
(-5690 4360);
DISPLAY 0.680851 (-5690 4360);
PAINT MONO (-5690 4360);
FORCEPROP 0 LASTPIN (-5700 4300) $PN EG17
J 0
(-5690 4310);
DISPLAY 0.680851 (-5690 4310);
PAINT MONO (-5690 4310);
FORCEPROP 0 LASTPIN (-5700 4250) $PN EG20
J 0
(-5690 4260);
DISPLAY 0.680851 (-5690 4260);
PAINT MONO (-5690 4260);
FORCEPROP 0 LASTPIN (-5700 4200) $PN EP17
J 0
(-5690 4210);
DISPLAY 0.680851 (-5690 4210);
PAINT MONO (-5690 4210);
FORCEPROP 0 LASTPIN (-5700 4150) $PN EP20
J 0
(-5690 4160);
DISPLAY 0.680851 (-5690 4160);
PAINT MONO (-5690 4160);
FORCEPROP 0 LASTPIN (-5700 4100) $PN T17
J 0
(-5690 4110);
DISPLAY 0.680851 (-5690 4110);
PAINT MONO (-5690 4110);
FORCEPROP 0 LASTPIN (-5700 4050) $PN T20
J 0
(-5690 4060);
DISPLAY 0.680851 (-5690 4060);
PAINT MONO (-5690 4060);
FORCEPROP 0 LASTPIN (-5700 3900) $PN BL17
J 0
(-5690 3910);
DISPLAY 0.680851 (-5690 3910);
PAINT MONO (-5690 3910);
FORCEPROP 0 LASTPIN (-5700 3850) $PN BL20
J 0
(-5690 3860);
DISPLAY 0.680851 (-5690 3860);
PAINT MONO (-5690 3860);
FORCEPROP 0 LASTPIN (-5700 3800) $PN CW17
J 0
(-5690 3810);
DISPLAY 0.680851 (-5690 3810);
PAINT MONO (-5690 3810);
FORCEPROP 0 LASTPIN (-5700 3750) $PN CW20
J 0
(-5690 3760);
DISPLAY 0.680851 (-5690 3760);
PAINT MONO (-5690 3760);
FORCEPROP 0 LASTPIN (-6850 3900) $PN G1
J 2
(-6860 3910);
DISPLAY 0.680851 (-6860 3910);
PAINT MONO (-6860 3910);
FORCEPROP 2 LAST PART_TYPE SMLF
J 0
(-6700 5425);
DISPLAY 0.680851 (-6700 5425);
FORCEPROP 2 LAST VALUE PT5161LRS
J 0
(-6700 5375);
DISPLAY 0.680851 (-6700 5375);
FORCEPROP 1 LAST MATERIAL IC
J 0
(-6700 5175);
DISPLAY 0.723404 (-6700 5175);
PAINT GREEN (-6700 5175);
FORCEPROP 1 LAST NEEDS_NO_SIZE TRUE
J 0
(-6250 4400);
DISPLAY 0.723404 (-6250 4400);
PAINT GREEN (-6250 4400);
DISPLAY INVISIBLE (-6250 4400);
FORCEPROP 1 LAST CDS_LMAN_SYM_OUTLINE -450,750,400,-750
J 0
(-6250 4400);
DISPLAY 0.468085 (-6250 4400);
PAINT GREEN (-6250 4400);
DISPLAY INVISIBLE (-6250 4400);
FORCEPROP 2 LAST CDS_LIB pure_quanta
J 0
(-6250 4400);
DISPLAY INVISIBLE (-6250 4400);
FORCEPROP 1 LAST PATH I7
J 0
(-6250 4400);
DISPLAY 0.723404 (-6250 4400);
PAINT GREEN (-6250 4400);
DISPLAY INVISIBLE (-6250 4400);
FORCEPROP 1 LAST PART_NUMBER AJ051610U03
J 0
(-6700 5250);
DISPLAY 0.723404 (-6700 5250);
PAINT GREEN (-6700 5250);
DISPLAY INVISIBLE (-6700 5250);
FORCEADD P1V0..1
(-4400 4050);
FORCEPROP 3 LASTPIN (-4400 4000) SIG_NAME P0V9_CPU1_RT_2D\g
J 0
(-4390 4010);
DISPLAY 0.659574 (-4390 4010);
PAINT MONO (-4390 4010);
DISPLAY INVISIBLE (-4390 4010);
FORCEPROP 1 LAST HDL_POWER P0V9_CPU1_RT_2D
J 1
(-4400 4100);
DISPLAY 0.489362 (-4400 4100);
PAINT SKYBLUE (-4400 4100);
FORCEPROP 2 LAST CDS_LIB pure_quanta_power
J 0
(-4400 4050);
DISPLAY INVISIBLE (-4400 4050);
FORCEPROP 1 LAST PATH I8
J 0
(-4350 4075);
DISPLAY 0.872340 (-4350 4075);
PAINT AQUA (-4350 4075);
DISPLAY INVISIBLE (-4350 4075);
FORCEADD P1V0..1
(-8100 4650);
FORCEPROP 3 LASTPIN (-8100 4600) SIG_NAME P1V8_CPU1_RT2_1A_1D\g
J 0
(-8090 4610);
DISPLAY 0.659574 (-8090 4610);
PAINT MONO (-8090 4610);
DISPLAY INVISIBLE (-8090 4610);
FORCEPROP 1 LAST HDL_POWER P1V8_CPU1_RT2_1A_1D
J 1
(-8100 4700);
DISPLAY 0.489362 (-8100 4700);
PAINT SKYBLUE (-8100 4700);
FORCEPROP 2 LAST CDS_LIB pure_quanta_power
J 0
(-8100 4650);
DISPLAY INVISIBLE (-8100 4650);
FORCEPROP 1 LAST PATH I9
J 0
(-8050 4675);
DISPLAY 0.872340 (-8050 4675);
PAINT AQUA (-8050 4675);
DISPLAY INVISIBLE (-8050 4675);
FORCEADD QUANTA_TITLE_BLOCK_C..1
(0 0);
FORCEPROP 0 LAST CDS_CON_LAST_MODIFIED Thu Sep 14 16:13:05 2023
J 0
(-1885 15);
DISPLAY INVISIBLE (-1885 15);
FORCEPROP 1 LAST CUSTOM_TXT_CDS <CON_LAST_MODIFIED>
J 0
(-1885 15);
DISPLAY 0.978723 (-1885 15);
FORCEPROP 2 LAST CUSTOM_TXT_CDS <XR_PAGE_TITLE>
J 0
(-7890 5250);
DISPLAY 0.638298 (-7890 5250);
PAINT PINK (-7890 5250);
DISPLAY INVISIBLE (-7890 5250);
FORCEPROP 1 LAST CUSTOM_TXT_CDS <NAME_2>
J 0
(-3175 50);
FORCEPROP 1 LAST CUSTOM_TXT_CDS <NAME_1>
J 0
(-3175 175);
FORCEPROP 1 LAST CUSTOM_TXT_CDS <Q_NUMBER>
J 0
(-1403 103);
DISPLAY 1.212766 (-1403 103);
FORCEPROP 1 LAST CUSTOM_TXT_CDS <Q_PROJ>
J 0
(-2382 102);
DISPLAY 1.212766 (-2382 102);
FORCEPROP 1 LAST CUSTOM_TXT_CDS <Q_REV>
J 0
(-184 103);
DISPLAY 1.212766 (-184 103);
FORCEPROP 1 LAST CUSTOM_TXT_CDS <CON_PAGE_NUM> OF <CON_TOTAL_PAGES>
J 0
(-446 18);
DISPLAY 0.978723 (-446 18);
FORCEPROP 1 LAST Q_TITLE RETIMER_CPU1_P2 POWER(6)
J 0
(-9366 26);
DISPLAY 2.446809 (-9366 26);
PAINT GREEN (-9366 26);
FORCEPROP 2 LAST CDS_LIB pure_quanta
J 0
(0 0);
DISPLAY INVISIBLE (0 0);
FORCEPROP 1 LAST CDS_LMAN_SYM_OUTLINE -9475,6775,100,-125
J 0
(0 0);
DISPLAY 0.468085 (0 0);
PAINT GREEN (0 0);
DISPLAY INVISIBLE (0 0);
FORCEPROP 2 LAST PAGE_BORDER TRUE
J 0
(-7890 5250);
DISPLAY 0.638298 (-7890 5250);
PAINT PINK (-7890 5250);
DISPLAY INVISIBLE (-7890 5250);
FORCEPROP 2 LAST CDS_XR_PAGE_TITLE CR-344 : @T6G_MB_LIB.T6G(SCH_1):PAGE344
J 0
(-7890 5250);
DISPLAY 0.638298 (-7890 5250);
PAINT PINK (-7890 5250);
DISPLAY INVISIBLE (-7890 5250);
FORCEPROP 1 LAST Q_DEPT BU9
J 1
(-3763 49);
DISPLAY 1.957447 (-3763 49);
PAINT GREEN (-3763 49);
DISPLAY INVISIBLE (-3763 49);
FORCEPROP 1 LAST COMMENT_BODY TRUE
J 0
(12 -13);
DISPLAY 0.978723 (12 -13);
PAINT GREEN (12 -13);
DISPLAY INVISIBLE (12 -13);
FORCEADD DNS..2
(-8375 4150);
PAINT RED (-8375 4150);
FORCEPROP 2 LAST CDS_LIB mstr_misc
J 0
(-8375 4150);
DISPLAY INVISIBLE (-8375 4150);
FORCEPROP 1 LAST COMMENT_BODY TRUE
J 0
(-8375 4150);
DISPLAY INVISIBLE (-8375 4150);
WIRE 16 -1 (-1200 1400)(-1200 1250);
WIRE 16 -1 (-1050 1950)(-1050 1800);
WIRE 16 -1 (-8425 4325)(-8425 4250);
WIRE 16 -1 (-7400 3500)(-7400 3400);
WIRE 16 -1 (-6850 3900)(-7400 3900);
WIRE 16 -1 (-7400 3900)(-7400 3700);
WIRE 16 -1 (-7400 3900)(-8425 3900);
FORCEPROP 2 LAST SIG_NAME RT_CPU1_P2_VQPS
J 0
(-7610 3910);
DISPLAY 0.680851 (-7610 3910);
PAINT SKYBLUE (-7610 3910);
FORCEPROP 2 LASTPROP $XRERR UNIQUE?
J 0
(-7850 3910);
DISPLAY 0.638298 (-7850 3910);
PAINT MONO (-7850 3910);
DISPLAY INVISIBLE (-7850 3910);
WIRE 16 -1 (-8425 4050)(-8425 3900);
WIRE 16 -1 (-6850 4350)(-8100 4350);
WIRE 16 -1 (-8100 4600)(-8100 4350);
WIRE 16 -1 (-1525 5825)(-1525 5775);
WIRE 16 -1 (-1525 5825)(-1725 5825);
WIRE 16 -1 (-1525 5775)(-1525 5725);
WIRE 16 -1 (-1525 5775)(-1725 5775);
WIRE 16 -1 (-1525 5725)(-1525 5675);
WIRE 16 -1 (-1525 5725)(-1725 5725);
WIRE 16 -1 (-1525 5675)(-1525 5625);
WIRE 16 -1 (-1525 5675)(-1725 5675);
WIRE 16 -1 (-1525 5625)(-1525 5575);
WIRE 16 -1 (-1525 5625)(-1725 5625);
WIRE 16 -1 (-1525 5575)(-1525 5525);
WIRE 16 -1 (-1525 5575)(-1725 5575);
WIRE 16 -1 (-1525 5525)(-1525 5475);
WIRE 16 -1 (-1525 5525)(-1725 5525);
WIRE 16 -1 (-1525 5475)(-1525 5425);
WIRE 16 -1 (-1525 5475)(-1725 5475);
WIRE 16 -1 (-1525 5425)(-1525 5375);
WIRE 16 -1 (-1525 5425)(-1725 5425);
WIRE 16 -1 (-1525 5375)(-1525 5325);
WIRE 16 -1 (-1525 5375)(-1725 5375);
WIRE 16 -1 (-1525 5325)(-1525 5275);
WIRE 16 -1 (-1525 5325)(-1725 5325);
WIRE 16 -1 (-1525 5275)(-1525 5225);
WIRE 16 -1 (-1525 5275)(-1725 5275);
WIRE 16 -1 (-1525 5225)(-1525 5175);
WIRE 16 -1 (-1525 5225)(-1725 5225);
WIRE 16 -1 (-1525 5175)(-1525 5125);
WIRE 16 -1 (-1525 5175)(-1725 5175);
WIRE 16 -1 (-1525 5125)(-1725 5125);
WIRE 16 -1 (-1525 5125)(-1525 5075);
WIRE 16 -1 (-1525 5075)(-1525 5025);
WIRE 16 -1 (-1525 5075)(-1725 5075);
WIRE 16 -1 (-1525 5025)(-1525 4975);
WIRE 16 -1 (-1525 5025)(-1725 5025);
WIRE 16 -1 (-1525 4975)(-1525 4925);
WIRE 16 -1 (-1525 4975)(-1725 4975);
WIRE 16 -1 (-1525 4925)(-1525 4875);
WIRE 16 -1 (-1525 4925)(-1725 4925);
WIRE 16 -1 (-1525 4875)(-1525 4825);
WIRE 16 -1 (-1525 4875)(-1725 4875);
WIRE 16 -1 (-1525 4825)(-1525 4775);
WIRE 16 -1 (-1525 4825)(-1725 4825);
WIRE 16 -1 (-1525 4775)(-1525 4725);
WIRE 16 -1 (-1525 4775)(-1725 4775);
WIRE 16 -1 (-1525 4725)(-1525 4675);
WIRE 16 -1 (-1525 4725)(-1725 4725);
WIRE 16 -1 (-1525 4675)(-1525 4625);
WIRE 16 -1 (-1525 4675)(-1725 4675);
WIRE 16 -1 (-1525 4625)(-1525 4575);
WIRE 16 -1 (-1525 4625)(-1725 4625);
WIRE 16 -1 (-1525 4575)(-1525 4525);
WIRE 16 -1 (-1525 4575)(-1725 4575);
WIRE 16 -1 (-1525 4525)(-1525 4475);
WIRE 16 -1 (-1525 4525)(-1725 4525);
WIRE 16 -1 (-1525 4475)(-1525 4425);
WIRE 16 -1 (-1525 4475)(-1725 4475);
WIRE 16 -1 (-1525 4425)(-1525 4375);
WIRE 16 -1 (-1525 4425)(-1725 4425);
WIRE 16 -1 (-1525 4375)(-1525 4325);
WIRE 16 -1 (-1525 4375)(-1725 4375);
WIRE 16 -1 (-1525 4325)(-1525 4275);
WIRE 16 -1 (-1525 4325)(-1725 4325);
WIRE 16 -1 (-1525 4275)(-1525 4225);
WIRE 16 -1 (-1525 4275)(-1725 4275);
WIRE 16 -1 (-1525 4225)(-1525 4175);
WIRE 16 -1 (-1525 4225)(-1725 4225);
WIRE 16 -1 (-1525 4175)(-1525 4125);
WIRE 16 -1 (-1525 4175)(-1725 4175);
WIRE 16 -1 (-1525 4125)(-1725 4125);
WIRE 16 -1 (-1525 4125)(-1525 4075);
WIRE 16 -1 (-1525 4075)(-1525 4025);
WIRE 16 -1 (-1525 4075)(-1725 4075);
WIRE 16 -1 (-1525 4025)(-1525 3975);
WIRE 16 -1 (-1525 4025)(-1725 4025);
WIRE 16 -1 (-1525 3975)(-1525 3925);
WIRE 16 -1 (-1525 3975)(-1725 3975);
WIRE 16 -1 (-1525 3925)(-1525 3875);
WIRE 16 -1 (-1525 3925)(-1725 3925);
WIRE 16 -1 (-1525 3875)(-1525 3825);
WIRE 16 -1 (-1525 3875)(-1725 3875);
WIRE 16 -1 (-1525 3825)(-1525 3775);
WIRE 16 -1 (-1525 3825)(-1725 3825);
WIRE 16 -1 (-1525 3775)(-1525 3725);
WIRE 16 -1 (-1525 3775)(-1725 3775);
WIRE 16 -1 (-1525 3725)(-1525 3675);
WIRE 16 -1 (-1525 3725)(-1725 3725);
WIRE 16 -1 (-1525 3675)(-1525 3625);
WIRE 16 -1 (-1525 3675)(-1725 3675);
WIRE 16 -1 (-1525 3625)(-1525 3575);
WIRE 16 -1 (-1525 3625)(-1725 3625);
WIRE 16 -1 (-1525 3575)(-1525 3525);
WIRE 16 -1 (-1525 3575)(-1725 3575);
WIRE 16 -1 (-1525 3525)(-1525 3475);
WIRE 16 -1 (-1525 3525)(-1725 3525);
WIRE 16 -1 (-1525 3475)(-1525 3425);
WIRE 16 -1 (-1525 3475)(-1725 3475);
WIRE 16 -1 (-1525 3425)(-1525 3375);
WIRE 16 -1 (-1525 3425)(-1725 3425);
WIRE 16 -1 (-1525 3375)(-1525 3325);
WIRE 16 -1 (-1525 3375)(-1725 3375);
WIRE 16 -1 (-1525 3325)(-1525 3275);
WIRE 16 -1 (-1525 3325)(-1725 3325);
WIRE 16 -1 (-1525 3275)(-1525 3225);
WIRE 16 -1 (-1525 3275)(-1725 3275);
WIRE 16 -1 (-1525 3225)(-1525 3175);
WIRE 16 -1 (-1525 3225)(-1725 3225);
WIRE 16 -1 (-1525 3175)(-1525 3125);
WIRE 16 -1 (-1525 3175)(-1725 3175);
WIRE 16 -1 (-1525 3125)(-1525 3075);
WIRE 16 -1 (-1525 3125)(-1725 3125);
WIRE 16 -1 (-1525 3075)(-1725 3075);
WIRE 16 -1 (-1525 3075)(-1525 3025);
WIRE 16 -1 (-1525 3025)(-1525 2975);
WIRE 16 -1 (-1525 3025)(-1725 3025);
WIRE 16 -1 (-1525 2975)(-1525 2925);
WIRE 16 -1 (-1525 2975)(-1725 2975);
WIRE 16 -1 (-1525 2925)(-1525 2875);
WIRE 16 -1 (-1525 2925)(-1725 2925);
WIRE 16 -1 (-1525 2875)(-1525 2825);
WIRE 16 -1 (-1525 2875)(-1725 2875);
WIRE 16 -1 (-1525 2825)(-1525 2775);
WIRE 16 -1 (-1525 2825)(-1725 2825);
WIRE 16 -1 (-1525 2775)(-1525 2725);
WIRE 16 -1 (-1525 2775)(-1725 2775);
WIRE 16 -1 (-1525 2725)(-1525 2675);
WIRE 16 -1 (-1525 2725)(-1725 2725);
WIRE 16 -1 (-1525 2675)(-1525 2625);
WIRE 16 -1 (-1525 2675)(-1725 2675);
WIRE 16 -1 (-1525 2625)(-1525 2575);
WIRE 16 -1 (-1525 2625)(-1725 2625);
WIRE 16 -1 (-1525 2575)(-1525 2525);
WIRE 16 -1 (-1525 2575)(-1725 2575);
WIRE 16 -1 (-1525 2525)(-1525 2475);
WIRE 16 -1 (-1525 2525)(-1725 2525);
WIRE 16 -1 (-1525 2475)(-1525 2425);
WIRE 16 -1 (-1525 2475)(-1725 2475);
WIRE 16 -1 (-1525 2425)(-1525 2400);
WIRE 16 -1 (-1525 2425)(-1725 2425);
WIRE 16 -1 (-1525 2400)(-825 2400);
WIRE 16 -1 (-825 2400)(-825 2350);
WIRE 16 -1 (-1200 1875)(-1200 1825);
WIRE 16 -1 (-1200 1925)(-1200 1875);
WIRE 16 -1 (-1200 1875)(-1725 1875);
WIRE 16 -1 (-1200 1825)(-1200 1775);
WIRE 16 -1 (-1200 1825)(-1725 1825);
WIRE 16 -1 (-1200 1775)(-1200 1600);
WIRE 16 -1 (-1200 1775)(-1725 1775);
WIRE 16 -1 (-1200 1975)(-1200 1925);
WIRE 16 -1 (-1200 1925)(-1725 1925);
WIRE 16 -1 (-1200 2025)(-1200 1975);
WIRE 16 -1 (-1200 1975)(-1725 1975);
WIRE 16 -1 (-1200 2075)(-1200 2025);
WIRE 16 -1 (-1200 2025)(-1725 2025);
WIRE 16 -1 (-1200 2125)(-1200 2075);
WIRE 16 -1 (-1200 2075)(-1725 2075);
WIRE 16 -1 (-1200 2175)(-1200 2125);
WIRE 16 -1 (-1200 2125)(-1725 2125);
WIRE 16 -1 (-1200 2225)(-1200 2175);
WIRE 16 -1 (-1200 2175)(-1725 2175);
WIRE 16 -1 (-1200 2275)(-1200 2225);
WIRE 16 -1 (-1200 2225)(-1725 2225);
WIRE 16 -1 (-1200 2275)(-1725 2275);
FORCEPROP 2 LAST SIG_NAME NCF_CPU1_P2_GND
J 0
(-1610 2285);
DISPLAY 0.553191 (-1610 2285);
FORCEPROP 2 LASTPROP $XRERR UNIQUE?
J 0
(-1850 2285);
DISPLAY 0.638298 (-1850 2285);
PAINT MONO (-1850 2285);
DISPLAY INVISIBLE (-1850 2285);
WIRE 16 -1 (-2675 5825)(-2875 5825);
WIRE 16 -1 (-2875 5825)(-2875 5775);
WIRE 16 -1 (-2675 5775)(-2875 5775);
WIRE 16 -1 (-2875 5775)(-2875 5725);
WIRE 16 -1 (-2675 5725)(-2875 5725);
WIRE 16 -1 (-2875 5725)(-2875 5675);
WIRE 16 -1 (-2675 5675)(-2875 5675);
WIRE 16 -1 (-2875 5675)(-2875 5625);
WIRE 16 -1 (-2675 5625)(-2875 5625);
WIRE 16 -1 (-2875 5625)(-2875 5575);
WIRE 16 -1 (-2675 5575)(-2875 5575);
WIRE 16 -1 (-2875 5575)(-2875 5525);
WIRE 16 -1 (-2675 5525)(-2875 5525);
WIRE 16 -1 (-2875 5525)(-2875 5475);
WIRE 16 -1 (-2675 5475)(-2875 5475);
WIRE 16 -1 (-2875 5475)(-2875 5425);
WIRE 16 -1 (-2675 5425)(-2875 5425);
WIRE 16 -1 (-2875 5425)(-2875 5375);
WIRE 16 -1 (-2675 5375)(-2875 5375);
WIRE 16 -1 (-2875 5375)(-2875 5325);
WIRE 16 -1 (-2675 5325)(-2875 5325);
WIRE 16 -1 (-2875 5325)(-2875 5275);
WIRE 16 -1 (-2675 5275)(-2875 5275);
WIRE 16 -1 (-2875 5275)(-2875 5225);
WIRE 16 -1 (-2675 5225)(-2875 5225);
WIRE 16 -1 (-2875 5225)(-2875 5175);
WIRE 16 -1 (-2675 5175)(-2875 5175);
WIRE 16 -1 (-2875 5175)(-2875 5125);
WIRE 16 -1 (-2675 5125)(-2875 5125);
WIRE 16 -1 (-2875 5125)(-2875 5075);
WIRE 16 -1 (-2675 5075)(-2875 5075);
WIRE 16 -1 (-2875 5075)(-2875 5025);
WIRE 16 -1 (-2675 5025)(-2875 5025);
WIRE 16 -1 (-2875 5025)(-2875 4975);
WIRE 16 -1 (-2675 4975)(-2875 4975);
WIRE 16 -1 (-2875 4975)(-2875 4925);
WIRE 16 -1 (-2675 4925)(-2875 4925);
WIRE 16 -1 (-2875 4925)(-2875 4875);
WIRE 16 -1 (-2675 4875)(-2875 4875);
WIRE 16 -1 (-2875 4875)(-2875 4825);
WIRE 16 -1 (-2675 4825)(-2875 4825);
WIRE 16 -1 (-2875 4825)(-2875 4775);
WIRE 16 -1 (-2675 4775)(-2875 4775);
WIRE 16 -1 (-2875 4775)(-2875 4725);
WIRE 16 -1 (-2675 4725)(-2875 4725);
WIRE 16 -1 (-2875 4725)(-2875 4675);
WIRE 16 -1 (-2675 4675)(-2875 4675);
WIRE 16 -1 (-2875 4675)(-2875 4625);
WIRE 16 -1 (-2675 4625)(-2875 4625);
WIRE 16 -1 (-2875 4625)(-2875 4575);
WIRE 16 -1 (-2675 4575)(-2875 4575);
WIRE 16 -1 (-2875 4575)(-2875 4525);
WIRE 16 -1 (-2675 4525)(-2875 4525);
WIRE 16 -1 (-2875 4525)(-2875 4475);
WIRE 16 -1 (-2675 4475)(-2875 4475);
WIRE 16 -1 (-2875 4475)(-2875 4425);
WIRE 16 -1 (-2675 4425)(-2875 4425);
WIRE 16 -1 (-2875 4425)(-2875 4375);
WIRE 16 -1 (-2675 4375)(-2875 4375);
WIRE 16 -1 (-2875 4375)(-2875 4325);
WIRE 16 -1 (-2675 4325)(-2875 4325);
WIRE 16 -1 (-2875 4325)(-2875 4275);
WIRE 16 -1 (-2675 4275)(-2875 4275);
WIRE 16 -1 (-2875 4275)(-2875 4225);
WIRE 16 -1 (-2675 4225)(-2875 4225);
WIRE 16 -1 (-2875 4225)(-2875 4175);
WIRE 16 -1 (-2675 4175)(-2875 4175);
WIRE 16 -1 (-2875 4175)(-2875 4125);
WIRE 16 -1 (-2675 4125)(-2875 4125);
WIRE 16 -1 (-2875 4125)(-2875 4075);
WIRE 16 -1 (-2675 4075)(-2875 4075);
WIRE 16 -1 (-2875 4075)(-2875 4025);
WIRE 16 -1 (-2675 4025)(-2875 4025);
WIRE 16 -1 (-2875 4025)(-2875 3975);
WIRE 16 -1 (-2675 3975)(-2875 3975);
WIRE 16 -1 (-2875 3975)(-2875 3925);
WIRE 16 -1 (-2675 3925)(-2875 3925);
WIRE 16 -1 (-2875 3925)(-2875 3875);
WIRE 16 -1 (-2675 3875)(-2875 3875);
WIRE 16 -1 (-2875 3875)(-2875 3825);
WIRE 16 -1 (-2675 3825)(-2875 3825);
WIRE 16 -1 (-2875 3825)(-2875 3775);
WIRE 16 -1 (-2675 3775)(-2875 3775);
WIRE 16 -1 (-2875 3775)(-2875 3725);
WIRE 16 -1 (-2675 3725)(-2875 3725);
WIRE 16 -1 (-2875 3725)(-2875 3675);
WIRE 16 -1 (-2675 3675)(-2875 3675);
WIRE 16 -1 (-2875 3675)(-2875 3625);
WIRE 16 -1 (-2675 3625)(-2875 3625);
WIRE 16 -1 (-2875 3625)(-2875 3575);
WIRE 16 -1 (-2675 3575)(-2875 3575);
WIRE 16 -1 (-2875 3575)(-2875 3525);
WIRE 16 -1 (-2675 3525)(-2875 3525);
WIRE 16 -1 (-2875 3525)(-2875 3475);
WIRE 16 -1 (-2675 3475)(-2875 3475);
WIRE 16 -1 (-2875 3475)(-2875 3425);
WIRE 16 -1 (-2675 3425)(-2875 3425);
WIRE 16 -1 (-2875 3425)(-2875 3375);
WIRE 16 -1 (-2675 3375)(-2875 3375);
WIRE 16 -1 (-2875 3375)(-2875 3325);
WIRE 16 -1 (-2675 3325)(-2875 3325);
WIRE 16 -1 (-2875 3325)(-2875 3275);
WIRE 16 -1 (-2675 3275)(-2875 3275);
WIRE 16 -1 (-2875 3275)(-2875 3225);
WIRE 16 -1 (-2675 3225)(-2875 3225);
WIRE 16 -1 (-2875 3225)(-2875 3175);
WIRE 16 -1 (-2675 3175)(-2875 3175);
WIRE 16 -1 (-2875 3175)(-2875 3125);
WIRE 16 -1 (-2675 3125)(-2875 3125);
WIRE 16 -1 (-2875 3125)(-2875 3075);
WIRE 16 -1 (-2675 3075)(-2875 3075);
WIRE 16 -1 (-2875 3075)(-2875 3025);
WIRE 16 -1 (-2675 3025)(-2875 3025);
WIRE 16 -1 (-2875 3025)(-2875 2975);
WIRE 16 -1 (-2675 2975)(-2875 2975);
WIRE 16 -1 (-2875 2975)(-2875 2925);
WIRE 16 -1 (-2675 2925)(-2875 2925);
WIRE 16 -1 (-2875 2925)(-2875 2875);
WIRE 16 -1 (-2675 2875)(-2875 2875);
WIRE 16 -1 (-2875 2875)(-2875 2825);
WIRE 16 -1 (-2675 2825)(-2875 2825);
WIRE 16 -1 (-2875 2825)(-2875 2775);
WIRE 16 -1 (-2675 2775)(-2875 2775);
WIRE 16 -1 (-2875 2775)(-2875 2725);
WIRE 16 -1 (-2675 2725)(-2875 2725);
WIRE 16 -1 (-2875 2725)(-2875 2675);
WIRE 16 -1 (-2675 2675)(-2875 2675);
WIRE 16 -1 (-2875 2675)(-2875 2625);
WIRE 16 -1 (-2675 2625)(-2875 2625);
WIRE 16 -1 (-2875 2625)(-2875 2575);
WIRE 16 -1 (-2675 2575)(-2875 2575);
WIRE 16 -1 (-2875 2575)(-2875 2525);
WIRE 16 -1 (-2675 2525)(-2875 2525);
WIRE 16 -1 (-2875 2525)(-2875 2475);
WIRE 16 -1 (-2675 2475)(-2875 2475);
WIRE 16 -1 (-2875 2475)(-2875 2425);
WIRE 16 -1 (-2675 2425)(-2875 2425);
WIRE 16 -1 (-2875 2425)(-2875 2375);
WIRE 16 -1 (-2675 2375)(-2875 2375);
WIRE 16 -1 (-2875 2375)(-2875 2325);
WIRE 16 -1 (-2675 2325)(-2875 2325);
WIRE 16 -1 (-2875 2325)(-2875 2275);
WIRE 16 -1 (-2675 2275)(-2875 2275);
WIRE 16 -1 (-2875 2275)(-2875 2225);
WIRE 16 -1 (-2675 2225)(-2875 2225);
WIRE 16 -1 (-2875 2225)(-2875 2175);
WIRE 16 -1 (-2675 2175)(-2875 2175);
WIRE 16 -1 (-2875 2175)(-2875 2125);
WIRE 16 -1 (-2675 2125)(-2875 2125);
WIRE 16 -1 (-2875 2125)(-2875 2075);
WIRE 16 -1 (-2675 2075)(-2875 2075);
WIRE 16 -1 (-2875 2075)(-2875 2025);
WIRE 16 -1 (-2675 2025)(-2875 2025);
WIRE 16 -1 (-2875 2025)(-2875 1975);
WIRE 16 -1 (-2675 1975)(-2875 1975);
WIRE 16 -1 (-2875 1975)(-2875 1925);
WIRE 16 -1 (-2675 1925)(-2875 1925);
WIRE 16 -1 (-2875 1925)(-2875 1875);
WIRE 16 -1 (-2675 1875)(-2875 1875);
WIRE 16 -1 (-2875 1875)(-2875 1825);
WIRE 16 -1 (-2675 1825)(-2875 1825);
WIRE 16 -1 (-2875 1825)(-2875 1775);
WIRE 16 -1 (-2675 1775)(-2875 1775);
WIRE 16 -1 (-2875 1775)(-2875 1625);
WIRE 16 -1 (-1050 2325)(-1050 2150);
WIRE 16 -1 (-1725 2325)(-1050 2325);
FORCEPROP 2 LAST SIG_NAME NCF_A1_CPU1_P2_GND
J 0
(-1560 2335);
DISPLAY 0.553191 (-1560 2335);
FORCEPROP 2 LASTPROP $XRERR UNIQUE?
J 0
(-1800 2335);
DISPLAY 0.638298 (-1800 2335);
PAINT MONO (-1800 2335);
DISPLAY INVISIBLE (-1800 2335);
WIRE 16 -1 (-5450 4150)(-5450 4100);
WIRE 16 -1 (-5450 4200)(-5450 4150);
WIRE 16 -1 (-5700 4150)(-5450 4150);
WIRE 16 -1 (-5700 4100)(-5450 4100);
WIRE 16 -1 (-5450 4100)(-5450 4050);
WIRE 16 -1 (-5450 4050)(-5700 4050);
WIRE 16 -1 (-5450 4250)(-5450 4200);
WIRE 16 -1 (-5700 4200)(-5450 4200);
WIRE 16 -1 (-5450 4300)(-5450 4250);
WIRE 16 -1 (-5700 4250)(-5450 4250);
WIRE 16 -1 (-5450 4350)(-5450 4300);
WIRE 16 -1 (-5700 4300)(-5450 4300);
WIRE 16 -1 (-5450 4400)(-5450 4350);
WIRE 16 -1 (-5700 4350)(-5450 4350);
WIRE 16 -1 (-5450 4450)(-5450 4400);
WIRE 16 -1 (-5700 4400)(-5450 4400);
WIRE 16 -1 (-5450 4500)(-5450 4450);
WIRE 16 -1 (-5700 4450)(-5450 4450);
WIRE 16 -1 (-5450 4500)(-4425 4500);
WIRE 16 -1 (-5450 4500)(-5700 4500);
WIRE 16 -1 (-4425 5000)(-4425 4500);
WIRE 16 -1 (-5475 5000)(-4425 5000);
WIRE 16 -1 (-4425 5000)(-4425 5225);
WIRE 16 -1 (-5700 5000)(-5475 5000);
WIRE 16 -1 (-5475 5000)(-5475 4950);
WIRE 16 -1 (-5475 4950)(-5475 4900);
WIRE 16 -1 (-5700 4950)(-5475 4950);
WIRE 16 -1 (-5475 4900)(-5475 4850);
WIRE 16 -1 (-5700 4900)(-5475 4900);
WIRE 16 -1 (-5475 4850)(-5475 4800);
WIRE 16 -1 (-5700 4850)(-5475 4850);
WIRE 16 -1 (-5475 4800)(-5475 4750);
WIRE 16 -1 (-5700 4800)(-5475 4800);
WIRE 16 -1 (-5475 4750)(-5700 4750);
WIRE 16 -1 (-5375 3800)(-5375 3750);
WIRE 16 -1 (-5375 3850)(-5375 3800);
WIRE 16 -1 (-5700 3800)(-5375 3800);
WIRE 16 -1 (-5375 3750)(-5700 3750);
WIRE 16 -1 (-5375 3900)(-5375 3850);
WIRE 16 -1 (-5700 3850)(-5375 3850);
WIRE 16 -1 (-5375 3900)(-4400 3900);
WIRE 16 -1 (-5700 3900)(-5375 3900);
WIRE 16 -1 (-4400 4000)(-4400 3900);
WIRE 16 -1 (-5450 4650)(-5450 4600);
WIRE 16 -1 (-5450 4700)(-5450 4650);
WIRE 16 -1 (-5700 4650)(-5450 4650);
WIRE 16 -1 (-5450 4600)(-5450 4550);
WIRE 16 -1 (-5450 4600)(-5700 4600);
WIRE 16 -1 (-5450 4550)(-5700 4550);
WIRE 16 -1 (-5450 4700)(-5000 4700);
WIRE 16 -1 (-5700 4700)(-5450 4700);
WIRE 16 -1 (-5000 4700)(-5000 4750);
WIRE 16 -1 (-7275 4800)(-6850 4800);
WIRE 16 -1 (-7275 4850)(-7275 4800);
WIRE 16 -1 (-6850 4850)(-7275 4850);
WIRE 16 -1 (-7275 4900)(-7275 4850);
WIRE 16 -1 (-6850 4900)(-7275 4900);
WIRE 16 -1 (-7275 4950)(-7275 4900);
WIRE 16 -1 (-6850 4950)(-7275 4950);
WIRE 16 -1 (-7275 5000)(-7275 4950);
WIRE 16 -1 (-6850 5000)(-7275 5000);
WIRE 16 -1 (-7275 5000)(-7525 5000);
WIRE 16 -1 (-7525 5000)(-7525 5050);
DOT 1 (-7400 3900);
DOT 1 (-5375 3800);
DOT 1 (-5375 3850);
DOT 1 (-5450 4100);
DOT 1 (-5450 4150);
DOT 1 (-5450 4200);
DOT 1 (-5450 4300);
DOT 1 (-5450 4350);
DOT 1 (-5375 3900);
DOT 1 (-7275 5000);
DOT 1 (-5450 4450);
DOT 1 (-5450 4600);
DOT 1 (-5450 4650);
DOT 1 (-5450 4700);
DOT 1 (-5475 4800);
DOT 1 (-5475 4900);
DOT 1 (-5475 5000);
DOT 1 (-5475 4950);
DOT 1 (-2875 1825);
DOT 1 (-2875 1875);
DOT 1 (-2875 1925);
DOT 1 (-2875 1975);
DOT 1 (-2875 2025);
DOT 1 (-2875 2075);
DOT 1 (-2875 2125);
DOT 1 (-2875 2175);
DOT 1 (-2875 2275);
DOT 1 (-2875 2325);
DOT 1 (-1200 1775);
DOT 1 (-1200 1825);
DOT 1 (-1200 1975);
DOT 1 (-1200 1925);
DOT 1 (-1200 1875);
DOT 1 (-1200 2075);
DOT 1 (-1200 2225);
DOT 1 (-1200 2175);
DOT 1 (-2875 2375);
DOT 1 (-2875 2525);
DOT 1 (-2875 2425);
DOT 1 (-2875 2475);
DOT 1 (-2875 2575);
DOT 1 (-2875 2775);
DOT 1 (-2875 2725);
DOT 1 (-2875 2675);
DOT 1 (-2875 2825);
DOT 1 (-2875 2875);
DOT 1 (-2875 2925);
DOT 1 (-2875 3025);
DOT 1 (-2875 2975);
DOT 1 (-2875 3075);
DOT 1 (-2875 3125);
DOT 1 (-2875 3175);
DOT 1 (-2875 3275);
DOT 1 (-2875 3225);
DOT 1 (-2875 3325);
DOT 1 (-2875 3375);
DOT 1 (-2875 3425);
DOT 1 (-2875 3525);
DOT 1 (-2875 3475);
DOT 1 (-2875 3625);
DOT 1 (-2875 3575);
DOT 1 (-2875 3675);
DOT 1 (-2875 3775);
DOT 1 (-2875 3725);
DOT 1 (-2875 3875);
DOT 1 (-2875 3825);
DOT 1 (-2875 3925);
DOT 1 (-2875 3975);
DOT 1 (-2875 4025);
DOT 1 (-2875 4075);
DOT 1 (-2875 4125);
DOT 1 (-2875 4175);
DOT 1 (-2875 4225);
DOT 1 (-2875 4275);
DOT 1 (-2875 4325);
DOT 1 (-2875 4375);
DOT 1 (-1525 2475);
DOT 1 (-1525 2425);
DOT 1 (-1525 2575);
DOT 1 (-1525 2725);
DOT 1 (-1525 2775);
DOT 1 (-1525 2825);
DOT 1 (-1525 2975);
DOT 1 (-1525 2925);
DOT 1 (-1525 2875);
DOT 1 (-1525 3025);
DOT 1 (-1525 3075);
DOT 1 (-1525 3125);
DOT 1 (-1525 3225);
DOT 1 (-1525 3175);
DOT 1 (-1525 3275);
DOT 1 (-1525 3325);
DOT 1 (-1525 3375);
DOT 1 (-1525 3475);
DOT 1 (-1525 3425);
DOT 1 (-1525 3575);
DOT 1 (-1525 3525);
DOT 1 (-1525 3675);
DOT 1 (-1525 3725);
DOT 1 (-1525 3875);
DOT 1 (-1525 3825);
DOT 1 (-1525 3775);
DOT 1 (-1525 3925);
DOT 1 (-1525 3975);
DOT 1 (-1525 4025);
DOT 1 (-1525 4125);
DOT 1 (-1525 4075);
DOT 1 (-1525 4175);
DOT 1 (-1525 4225);
DOT 1 (-1525 4275);
DOT 1 (-1525 4375);
DOT 1 (-1525 4325);
DOT 1 (-4425 5000);
DOT 1 (-2875 4425);
DOT 1 (-2875 4575);
DOT 1 (-2875 4525);
DOT 1 (-2875 4475);
DOT 1 (-2875 4625);
DOT 1 (-2875 4675);
DOT 1 (-2875 4825);
DOT 1 (-2875 4775);
DOT 1 (-2875 4725);
DOT 1 (-2875 4875);
DOT 1 (-2875 4925);
DOT 1 (-2875 4975);
DOT 1 (-2875 5025);
DOT 1 (-2875 5075);
DOT 1 (-2875 5125);
DOT 1 (-2875 5175);
DOT 1 (-2875 5225);
DOT 1 (-2875 5325);
DOT 1 (-2875 5275);
DOT 1 (-2875 5375);
DOT 1 (-2875 5425);
DOT 1 (-2875 5475);
DOT 1 (-2875 5575);
DOT 1 (-2875 5525);
DOT 1 (-2875 5625);
DOT 1 (-2875 5675);
DOT 1 (-2875 5725);
DOT 1 (-2875 5775);
DOT 1 (-1525 4425);
DOT 1 (-1525 4475);
DOT 1 (-1525 4525);
DOT 1 (-1525 4625);
DOT 1 (-1525 4575);
DOT 1 (-1525 4775);
DOT 1 (-1525 4725);
DOT 1 (-1525 4675);
DOT 1 (-1525 4825);
DOT 1 (-1525 4875);
DOT 1 (-1525 5025);
DOT 1 (-1525 4975);
DOT 1 (-1525 4925);
DOT 1 (-1525 5075);
DOT 1 (-1525 5125);
DOT 1 (-1525 5175);
DOT 1 (-1525 5275);
DOT 1 (-1525 5225);
DOT 1 (-1525 5325);
DOT 1 (-1525 5375);
DOT 1 (-1525 5425);
DOT 1 (-1525 5525);
DOT 1 (-1525 5475);
DOT 1 (-1525 5625);
DOT 1 (-1525 5675);
DOT 1 (-1525 5575);
DOT 1 (-1525 5725);
DOT 1 (-1525 5775);
DOT 1 (-1525 3625);
DOT 1 (-5450 4400);
DOT 1 (-1200 2025);
DOT 1 (-2875 2225);
DOT 1 (-2875 1775);
DOT 1 (-7275 4950);
DOT 1 (-7275 4850);
DOT 1 (-7275 4900);
DOT 1 (-5450 4500);
DOT 1 (-5475 4850);
DOT 1 (-5450 4250);
DOT 1 (-2875 2625);
DOT 1 (-1200 2125);
DOT 1 (-1525 2625);
DOT 1 (-1525 2525);
DOT 1 (-1525 2675);
QUIT
